(kicad_pcb
	(version 20260206)
	(generator "pcbnew")
	(generator_version "10.0")
	(general
		(thickness 1.6)
		(legacy_teardrops no)
	)
	(paper "A4")
	(title_block
		(title "v1-chassis-manager — T6M_CM_d_v01_1031_1645.brd")
		(comment 1 "Open CloudServer (Microsoft) / footprints 2164-2173 of 2512")
	)
	(layers
		(0 "F.Cu" signal "TOP")
		(4 "In1.Cu" signal "GND1")
		(6 "In2.Cu" signal "IN1")
		(8 "In3.Cu" signal "VCC1")
		(10 "In4.Cu" signal "VCC2")
		(12 "In5.Cu" signal "GND2")
		(14 "In6.Cu" signal "IN2")
		(16 "In7.Cu" signal "IN3")
		(18 "In8.Cu" signal "GND3")
		(2 "B.Cu" signal "BOTTOM")
		(9 "F.Adhes" user "F.Adhesive")
		(11 "B.Adhes" user "B.Adhesive")
		(13 "F.Paste" user "Package Geometry/Pastemask Top")
		(15 "B.Paste" user "Package Geometry/Pastemask Bottom")
		(5 "F.SilkS" user "Ref Des/Silkscreen Top")
		(7 "B.SilkS" user "Ref Des/Silkscreen Bottom")
		(1 "F.Mask" user "Board Geometry/Soldermask Top")
		(3 "B.Mask" user "Board Geometry/Soldermask Bottom")
		(17 "Dwgs.User" user "User.Drawings")
		(19 "Cmts.User" user "User.Comments")
		(21 "Eco1.User" user "User.Eco1")
		(23 "Eco2.User" user "User.Eco2")
		(25 "Edge.Cuts" user "Board Geometry/Outline")
		(27 "Margin" user)
		(31 "F.CrtYd" user "Package Geometry/Place Bound Top")
		(29 "B.CrtYd" user "Package Geometry/Place Bound Bottom")
		(35 "F.Fab" user "Ref Des/Assembly Top")
		(33 "B.Fab" user "Ref Des/Assembly Bottom")
	)
	(footprint ""
		(layer "B.Cu")
		(at 111.87176 -188.126624 90)
		(property "Reference" "R967"
			(at 4.080256 0.69596 270)
			(unlocked yes)
			(layer "B.SilkS")
			(effects
				(font
					(size 0.7874 0.5842)
					(thickness 0.1524)
				)
				(justify left mirror)
			)
		)
		(property "Value" ""
			(at 0 0 90)
			(layer "B.Fab")
			(effects
				(font
					(size 1.27 1.27)
				)
				(justify mirror)
			)
		)
		(duplicate_pad_numbers_are_jumpers no)
		(fp_line
			(start 0.7874 -0.4064)
			(end -0.7874 -0.4064)
			(stroke
				(width 0.1524)
				(type default)
			)
			(layer "B.SilkS")
		)
		(fp_line
			(start -0.7874 -0.4064)
			(end -0.7874 0.4064)
			(stroke
				(width 0.1524)
				(type default)
			)
			(layer "B.SilkS")
		)
		(fp_line
			(start 0.7874 0.4064)
			(end 0.7874 -0.4064)
			(stroke
				(width 0.1524)
				(type default)
			)
			(layer "B.SilkS")
		)
		(fp_line
			(start -0.7874 0.4064)
			(end 0.7874 0.4064)
			(stroke
				(width 0.1524)
				(type default)
			)
			(layer "B.SilkS")
		)
		(fp_poly
			(pts
				(xy 0.508 0.2794) (xy 0.508 0.2286) (xy 0.635 0.2286) (xy 0.635 -0.254) (xy 0.5334 -0.254) (xy 0.5334 -0.2794)
				(xy -0.5334 -0.2794) (xy -0.5334 -0.254) (xy -0.635 -0.254) (xy -0.635 0.254) (xy -0.5334 0.254)
				(xy -0.5334 0.2794)
			)
			(stroke
				(width 0)
				(type default)
			)
			(fill no)
			(layer "B.CrtYd")
		)
		(pad "1" smd rect
			(at -0.40005 0 270)
			(size 0.4572 0.508)
			(layers "B.Cu" "B.Mask" "B.Paste")
			(net "UART_T7_NODE3_RXD")
		)
		(pad "2" smd rect
			(at 0.40005 0 270)
			(size 0.4572 0.508)
			(layers "B.Cu" "B.Mask" "B.Paste")
			(net "UART_T7_NODE3_RXD_R")
		)
	)
	(footprint ""
		(layer "B.Cu")
		(at 43.702732 -94.40037 90)
		(property "Reference" "R128"
			(at -4.703318 -4.548378 270)
			(unlocked yes)
			(layer "B.SilkS")
			(effects
				(font
					(size 0.7874 0.5842)
					(thickness 0.1524)
				)
				(justify left mirror)
			)
		)
		(property "Value" ""
			(at 0 0 90)
			(layer "B.Fab")
			(effects
				(font
					(size 1.27 1.27)
				)
				(justify mirror)
			)
		)
		(duplicate_pad_numbers_are_jumpers no)
		(fp_line
			(start 0.7874 -0.4064)
			(end -0.7874 -0.4064)
			(stroke
				(width 0.1524)
				(type default)
			)
			(layer "B.SilkS")
		)
		(fp_line
			(start -0.7874 -0.4064)
			(end -0.7874 0.4064)
			(stroke
				(width 0.1524)
				(type default)
			)
			(layer "B.SilkS")
		)
		(fp_line
			(start 0.7874 0.4064)
			(end 0.7874 -0.4064)
			(stroke
				(width 0.1524)
				(type default)
			)
			(layer "B.SilkS")
		)
		(fp_line
			(start -0.7874 0.4064)
			(end 0.7874 0.4064)
			(stroke
				(width 0.1524)
				(type default)
			)
			(layer "B.SilkS")
		)
		(fp_poly
			(pts
				(xy 0.508 0.2794) (xy 0.508 0.2286) (xy 0.635 0.2286) (xy 0.635 -0.254) (xy 0.5334 -0.254) (xy 0.5334 -0.2794)
				(xy -0.5334 -0.2794) (xy -0.5334 -0.254) (xy -0.635 -0.254) (xy -0.635 0.254) (xy -0.5334 0.254)
				(xy -0.5334 0.2794)
			)
			(stroke
				(width 0)
				(type default)
			)
			(fill no)
			(layer "B.CrtYd")
		)
		(pad "1" smd rect
			(at -0.40005 0 270)
			(size 0.4572 0.508)
			(layers "B.Cu" "B.Mask" "B.Paste")
			(net "SMB_CPU_NODE1_MEM_ICS_DAT_R")
		)
		(pad "2" smd rect
			(at 0.40005 0 270)
			(size 0.4572 0.508)
			(layers "B.Cu" "B.Mask" "B.Paste")
			(net "SMB_MUX_CPU_ICS_NODE1_DAT")
		)
	)
	(footprint ""
		(layer "B.Cu")
		(at 90.81262 -175.038512)
		(property "Reference" "R700"
			(at 24.902414 20.083272 0)
			(unlocked yes)
			(layer "B.SilkS")
			(effects
				(font
					(size 0.7874 0.5842)
					(thickness 0.1524)
				)
				(justify left mirror)
			)
		)
		(property "Value" ""
			(at 0 0 0)
			(layer "B.Fab")
			(effects
				(font
					(size 1.27 1.27)
				)
				(justify mirror)
			)
		)
		(duplicate_pad_numbers_are_jumpers no)
		(fp_line
			(start -0.7874 -0.4064)
			(end -0.7874 0.4064)
			(stroke
				(width 0.1524)
				(type default)
			)
			(layer "B.SilkS")
		)
		(fp_line
			(start -0.7874 0.4064)
			(end 0.7874 0.4064)
			(stroke
				(width 0.1524)
				(type default)
			)
			(layer "B.SilkS")
		)
		(fp_line
			(start 0.7874 -0.4064)
			(end -0.7874 -0.4064)
			(stroke
				(width 0.1524)
				(type default)
			)
			(layer "B.SilkS")
		)
		(fp_line
			(start 0.7874 0.4064)
			(end 0.7874 -0.4064)
			(stroke
				(width 0.1524)
				(type default)
			)
			(layer "B.SilkS")
		)
		(fp_poly
			(pts
				(xy 0.508 0.2794) (xy 0.508 0.2286) (xy 0.635 0.2286) (xy 0.635 -0.254) (xy 0.5334 -0.254) (xy 0.5334 -0.2794)
				(xy -0.5334 -0.2794) (xy -0.5334 -0.254) (xy -0.635 -0.254) (xy -0.635 0.254) (xy -0.5334 0.254)
				(xy -0.5334 0.2794)
			)
			(stroke
				(width 0)
				(type default)
			)
			(fill no)
			(layer "B.CrtYd")
		)
		(pad "1" smd rect
			(at -0.40005 0 180)
			(size 0.4572 0.508)
			(layers "B.Cu" "B.Mask" "B.Paste")
			(net "T3_NODE4_EN")
		)
		(pad "2" smd rect
			(at 0.40005 0 180)
			(size 0.4572 0.508)
			(layers "B.Cu" "B.Mask" "B.Paste")
			(net "P5V_NODE1")
		)
	)
	(footprint ""
		(layer "B.Cu")
		(at 55.552086 -128.740662 180)
		(property "Reference" "C266"
			(at 41.609518 -53.38191 0)
			(unlocked yes)
			(layer "B.SilkS")
			(effects
				(font
					(size 0.7874 0.5842)
					(thickness 0.1524)
				)
				(justify left mirror)
			)
		)
		(property "Value" ""
			(at 0 0 0)
			(layer "B.Fab")
			(effects
				(font
					(size 1.27 1.27)
				)
				(justify mirror)
			)
		)
		(duplicate_pad_numbers_are_jumpers no)
		(fp_line
			(start 0.7874 0.4064)
			(end 0.7874 -0.4064)
			(stroke
				(width 0.1524)
				(type default)
			)
			(layer "B.SilkS")
		)
		(fp_line
			(start 0.7874 -0.4064)
			(end -0.7874 -0.4064)
			(stroke
				(width 0.1524)
				(type default)
			)
			(layer "B.SilkS")
		)
		(fp_line
			(start 0 0.381)
			(end 0 -0.381)
			(stroke
				(width 0.1524)
				(type default)
			)
			(layer "B.SilkS")
		)
		(fp_line
			(start -0.7874 0.4064)
			(end 0.7874 0.4064)
			(stroke
				(width 0.1524)
				(type default)
			)
			(layer "B.SilkS")
		)
		(fp_line
			(start -0.7874 -0.4064)
			(end -0.7874 0.4064)
			(stroke
				(width 0.1524)
				(type default)
			)
			(layer "B.SilkS")
		)
		(fp_poly
			(pts
				(xy 0.5334 0.254) (xy 0.635 0.254) (xy 0.635 0.2286) (xy 0.635 -0.254) (xy 0.5334 -0.254) (xy 0.5334 -0.2794)
				(xy -0.5334 -0.2794) (xy -0.5334 -0.254) (xy -0.635 -0.254) (xy -0.635 0.254) (xy -0.5334 0.254)
				(xy -0.5334 0.2794) (xy 0.508 0.2794) (xy 0.5334 0.2794)
			)
			(stroke
				(width 0)
				(type default)
			)
			(fill no)
			(layer "B.CrtYd")
		)
		(pad "1" smd rect
			(at -0.40005 0)
			(size 0.4572 0.508)
			(layers "B.Cu" "B.Mask" "B.Paste")
			(net "BMC_NODE1_MPLLAV33")
		)
		(pad "2" smd rect
			(at 0.40005 0)
			(size 0.4572 0.508)
			(layers "B.Cu" "B.Mask" "B.Paste")
			(net "GND")
		)
	)
	(footprint ""
		(layer "B.Cu")
		(at 130.521202 -34.973768)
		(property "Reference" "R1209"
			(at 5.29971 3.420618 0)
			(unlocked yes)
			(layer "B.SilkS")
			(effects
				(font
					(size 0.7874 0.5842)
					(thickness 0.1524)
				)
				(justify left mirror)
			)
		)
		(property "Value" ""
			(at 0 0 0)
			(layer "B.Fab")
			(effects
				(font
					(size 1.27 1.27)
				)
				(justify mirror)
			)
		)
		(duplicate_pad_numbers_are_jumpers no)
		(fp_line
			(start -0.7874 -0.4064)
			(end -0.7874 0.4064)
			(stroke
				(width 0.1524)
				(type default)
			)
			(layer "B.SilkS")
		)
		(fp_line
			(start -0.7874 0.4064)
			(end 0.7874 0.4064)
			(stroke
				(width 0.1524)
				(type default)
			)
			(layer "B.SilkS")
		)
		(fp_line
			(start 0.7874 -0.4064)
			(end -0.7874 -0.4064)
			(stroke
				(width 0.1524)
				(type default)
			)
			(layer "B.SilkS")
		)
		(fp_line
			(start 0.7874 0.4064)
			(end 0.7874 -0.4064)
			(stroke
				(width 0.1524)
				(type default)
			)
			(layer "B.SilkS")
		)
		(fp_poly
			(pts
				(xy 0.508 0.2794) (xy 0.508 0.2286) (xy 0.635 0.2286) (xy 0.635 -0.254) (xy 0.5334 -0.254) (xy 0.5334 -0.2794)
				(xy -0.5334 -0.2794) (xy -0.5334 -0.254) (xy -0.635 -0.254) (xy -0.635 0.254) (xy -0.5334 0.254)
				(xy -0.5334 0.2794)
			)
			(stroke
				(width 0)
				(type default)
			)
			(fill no)
			(layer "B.CrtYd")
		)
		(pad "1" smd rect
			(at -0.40005 0 180)
			(size 0.4572 0.508)
			(layers "B.Cu" "B.Mask" "B.Paste")
			(net "SIO_JTAG_CPLD3_TMS")
		)
		(pad "2" smd rect
			(at 0.40005 0 180)
			(size 0.4572 0.508)
			(layers "B.Cu" "B.Mask" "B.Paste")
			(net "GND")
		)
	)
	(footprint ""
		(layer "B.Cu")
		(at 52.301648 -125.133354)
		(property "Reference" "C286"
			(at -42.066464 53.341524 0)
			(unlocked yes)
			(layer "B.SilkS")
			(effects
				(font
					(size 0.7874 0.5842)
					(thickness 0.1524)
				)
				(justify mirror)
			)
		)
		(property "Value" ""
			(at 0 0 0)
			(layer "B.Fab")
			(effects
				(font
					(size 1.27 1.27)
				)
				(justify mirror)
			)
		)
		(duplicate_pad_numbers_are_jumpers no)
		(fp_line
			(start -1.2954 -0.5842)
			(end -1.2954 0.5842)
			(stroke
				(width 0.1524)
				(type default)
			)
			(layer "B.SilkS")
		)
		(fp_line
			(start -1.2954 0.5842)
			(end 1.2954 0.5842)
			(stroke
				(width 0.1524)
				(type default)
			)
			(layer "B.SilkS")
		)
		(fp_line
			(start 0 -0.5842)
			(end 0 0.5842)
			(stroke
				(width 0.1524)
				(type default)
			)
			(layer "B.SilkS")
		)
		(fp_line
			(start 1.2954 -0.5842)
			(end -1.2954 -0.5842)
			(stroke
				(width 0.1524)
				(type default)
			)
			(layer "B.SilkS")
		)
		(fp_line
			(start 1.2954 0.5842)
			(end 1.2954 -0.5842)
			(stroke
				(width 0.1524)
				(type default)
			)
			(layer "B.SilkS")
		)
		(fp_poly
			(pts
				(xy -0.8636 -0.4572) (xy -0.8636 -0.3556) (xy -1.143 -0.3556) (xy -1.143 0.3556) (xy -0.8636 0.3556)
				(xy -0.8636 0.4572) (xy 0.8636 0.4572) (xy 0.8636 0.3556) (xy 1.143 0.3556) (xy 1.143 -0.3556) (xy 0.8636 -0.3556)
				(xy 0.8636 -0.4572)
			)
			(stroke
				(width 0)
				(type default)
			)
			(fill no)
			(layer "B.CrtYd")
		)
		(fp_line
			(start -0.884936 -0.504952)
			(end -0.884936 0.504952)
			(stroke
				(width 0.1)
				(type default)
			)
			(layer "B.Fab")
		)
		(fp_line
			(start -0.884936 0.504952)
			(end 0.884936 0.504952)
			(stroke
				(width 0.1)
				(type default)
			)
			(layer "B.Fab")
		)
		(fp_line
			(start 0.884936 -0.504952)
			(end -0.884936 -0.504952)
			(stroke
				(width 0.1)
				(type default)
			)
			(layer "B.Fab")
		)
		(fp_line
			(start 0.884936 0.504952)
			(end 0.884936 -0.504952)
			(stroke
				(width 0.1)
				(type default)
			)
			(layer "B.Fab")
		)
		(pad "1" smd rect
			(at -0.7366 0 90)
			(size 0.7112 0.8128)
			(layers "B.Cu" "B.Mask" "B.Paste")
			(net "P1V26_BMC_NODE1")
		)
		(pad "2" smd rect
			(at 0.7366 0 90)
			(size 0.7112 0.8128)
			(layers "B.Cu" "B.Mask" "B.Paste")
			(net "GND")
		)
	)
	(footprint ""
		(layer "B.Cu")
		(at 163.890198 -148.85543 90)
		(property "Reference" "C459"
			(at -8.488426 0.2413 270)
			(unlocked yes)
			(layer "B.SilkS")
			(effects
				(font
					(size 0.7874 0.5842)
					(thickness 0.1524)
				)
				(justify left mirror)
			)
		)
		(property "Value" ""
			(at 0 0 90)
			(layer "B.Fab")
			(effects
				(font
					(size 1.27 1.27)
				)
				(justify mirror)
			)
		)
		(duplicate_pad_numbers_are_jumpers no)
		(fp_line
			(start 0.7874 -0.4064)
			(end -0.7874 -0.4064)
			(stroke
				(width 0.1524)
				(type default)
			)
			(layer "B.SilkS")
		)
		(fp_line
			(start -0.7874 -0.4064)
			(end -0.7874 0.4064)
			(stroke
				(width 0.1524)
				(type default)
			)
			(layer "B.SilkS")
		)
		(fp_line
			(start 0 0.381)
			(end 0 -0.381)
			(stroke
				(width 0.1524)
				(type default)
			)
			(layer "B.SilkS")
		)
		(fp_line
			(start 0.7874 0.4064)
			(end 0.7874 -0.4064)
			(stroke
				(width 0.1524)
				(type default)
			)
			(layer "B.SilkS")
		)
		(fp_line
			(start -0.7874 0.4064)
			(end 0.7874 0.4064)
			(stroke
				(width 0.1524)
				(type default)
			)
			(layer "B.SilkS")
		)
		(fp_poly
			(pts
				(xy 0.5334 0.254) (xy 0.635 0.254) (xy 0.635 0.2286) (xy 0.635 -0.254) (xy 0.5334 -0.254) (xy 0.5334 -0.2794)
				(xy -0.5334 -0.2794) (xy -0.5334 -0.254) (xy -0.635 -0.254) (xy -0.635 0.254) (xy -0.5334 0.254)
				(xy -0.5334 0.2794) (xy 0.508 0.2794) (xy 0.5334 0.2794)
			)
			(stroke
				(width 0)
				(type default)
			)
			(fill no)
			(layer "B.CrtYd")
		)
		(pad "1" smd rect
			(at -0.40005 0 270)
			(size 0.4572 0.508)
			(layers "B.Cu" "B.Mask" "B.Paste")
			(net "P1V9_LAN2")
		)
		(pad "2" smd rect
			(at 0.40005 0 270)
			(size 0.4572 0.508)
			(layers "B.Cu" "B.Mask" "B.Paste")
			(net "GND")
		)
	)
	(footprint ""
		(layer "B.Cu")
		(at 152.76576 -187.872624 -90)
		(property "Reference" "C654"
			(at -4.565396 3.44043 270)
			(unlocked yes)
			(layer "B.SilkS")
			(effects
				(font
					(size 0.7874 0.5842)
					(thickness 0.1524)
				)
				(justify left mirror)
			)
		)
		(property "Value" ""
			(at 0 0 90)
			(layer "B.Fab")
			(effects
				(font
					(size 1.27 1.27)
				)
				(justify mirror)
			)
		)
		(duplicate_pad_numbers_are_jumpers no)
		(fp_line
			(start -0.7874 0.4064)
			(end 0.7874 0.4064)
			(stroke
				(width 0.1524)
				(type default)
			)
			(layer "B.SilkS")
		)
		(fp_line
			(start 0.7874 0.4064)
			(end 0.7874 -0.4064)
			(stroke
				(width 0.1524)
				(type default)
			)
			(layer "B.SilkS")
		)
		(fp_line
			(start 0 0.381)
			(end 0 -0.381)
			(stroke
				(width 0.1524)
				(type default)
			)
			(layer "B.SilkS")
		)
		(fp_line
			(start -0.7874 -0.4064)
			(end -0.7874 0.4064)
			(stroke
				(width 0.1524)
				(type default)
			)
			(layer "B.SilkS")
		)
		(fp_line
			(start 0.7874 -0.4064)
			(end -0.7874 -0.4064)
			(stroke
				(width 0.1524)
				(type default)
			)
			(layer "B.SilkS")
		)
		(fp_poly
			(pts
				(xy 0.5334 0.254) (xy 0.635 0.254) (xy 0.635 0.2286) (xy 0.635 -0.254) (xy 0.5334 -0.254) (xy 0.5334 -0.2794)
				(xy -0.5334 -0.2794) (xy -0.5334 -0.254) (xy -0.635 -0.254) (xy -0.635 0.254) (xy -0.5334 0.254)
				(xy -0.5334 0.2794) (xy 0.508 0.2794) (xy 0.5334 0.2794)
			)
			(stroke
				(width 0)
				(type default)
			)
			(fill no)
			(layer "B.CrtYd")
		)
		(pad "1" smd rect
			(at -0.40005 0 90)
			(size 0.4572 0.508)
			(layers "B.Cu" "B.Mask" "B.Paste")
			(net "T11_NODE3_EN_R")
		)
		(pad "2" smd rect
			(at 0.40005 0 90)
			(size 0.4572 0.508)
			(layers "B.Cu" "B.Mask" "B.Paste")
			(net "GND")
		)
	)
	(footprint ""
		(layer "B.Cu")
		(at 127.416814 -124.224796 -90)
		(property "Reference" "L3"
			(at -2.121408 -0.1651 270)
			(unlocked yes)
			(layer "B.SilkS")
			(effects
				(font
					(size 0.7874 0.5842)
					(thickness 0.1524)
				)
				(justify left mirror)
			)
		)
		(property "Value" ""
			(at 0 0 90)
			(layer "B.Fab")
			(effects
				(font
					(size 1.27 1.27)
				)
				(justify mirror)
			)
		)
		(duplicate_pad_numbers_are_jumpers no)
		(fp_line
			(start -1.905 0.8636)
			(end 1.905 0.8636)
			(stroke
				(width 0.1524)
				(type default)
			)
			(layer "B.SilkS")
		)
		(fp_line
			(start -1.905 0.8382)
			(end -1.905 -0.8382)
			(stroke
				(width 0.1524)
				(type default)
			)
			(layer "B.SilkS")
		)
		(fp_line
			(start -0.127 0.8382)
			(end -0.127 -0.8382)
			(stroke
				(width 0.1524)
				(type default)
			)
			(layer "B.SilkS")
		)
		(fp_line
			(start 0.127 0.8382)
			(end 0.127 -0.8382)
			(stroke
				(width 0.1524)
				(type default)
			)
			(layer "B.SilkS")
		)
		(fp_line
			(start 1.905 0.8382)
			(end 1.905 -0.8382)
			(stroke
				(width 0.1524)
				(type default)
			)
			(layer "B.SilkS")
		)
		(fp_line
			(start 1.905 -0.8636)
			(end -1.905 -0.8636)
			(stroke
				(width 0.1524)
				(type default)
			)
			(layer "B.SilkS")
		)
		(fp_rect
			(start 1.524 0.7112)
			(end -1.524 -0.7366)
			(stroke
				(width 0)
				(type default)
			)
			(fill no)
			(layer "B.CrtYd")
		)
		(pad "1" smd rect
			(at -0.94996 0 90)
			(size 1.1176 1.3716)
			(layers "B.Cu" "B.Mask" "B.Paste")
			(net "P1V05_CLK_NODE1_R")
		)
		(pad "2" smd rect
			(at 0.94996 0 90)
			(size 1.1176 1.3716)
			(layers "B.Cu" "B.Mask" "B.Paste")
			(net "P1V05_CLK_NODE1")
		)
	)
	(footprint ""
		(layer "B.Cu")
		(at 78.83144 -177.585624 180)
		(property "Reference" "R696"
			(at -30.562296 -20.108164 0)
			(unlocked yes)
			(layer "B.SilkS")
			(effects
				(font
					(size 0.7874 0.5842)
					(thickness 0.1524)
				)
				(justify left mirror)
			)
		)
		(property "Value" ""
			(at 0 0 0)
			(layer "B.Fab")
			(effects
				(font
					(size 1.27 1.27)
				)
				(justify mirror)
			)
		)
		(duplicate_pad_numbers_are_jumpers no)
		(fp_line
			(start 0.7874 0.4064)
			(end 0.7874 -0.4064)
			(stroke
				(width 0.1524)
				(type default)
			)
			(layer "B.SilkS")
		)
		(fp_line
			(start 0.7874 -0.4064)
			(end -0.7874 -0.4064)
			(stroke
				(width 0.1524)
				(type default)
			)
			(layer "B.SilkS")
		)
		(fp_line
			(start -0.7874 0.4064)
			(end 0.7874 0.4064)
			(stroke
				(width 0.1524)
				(type default)
			)
			(layer "B.SilkS")
		)
		(fp_line
			(start -0.7874 -0.4064)
			(end -0.7874 0.4064)
			(stroke
				(width 0.1524)
				(type default)
			)
			(layer "B.SilkS")
		)
		(fp_poly
			(pts
				(xy 0.508 0.2794) (xy 0.508 0.2286) (xy 0.635 0.2286) (xy 0.635 -0.254) (xy 0.5334 -0.254) (xy 0.5334 -0.2794)
				(xy -0.5334 -0.2794) (xy -0.5334 -0.254) (xy -0.635 -0.254) (xy -0.635 0.254) (xy -0.5334 0.254)
				(xy -0.5334 0.2794)
			)
			(stroke
				(width 0)
				(type default)
			)
			(fill no)
			(layer "B.CrtYd")
		)
		(pad "1" smd rect
			(at -0.40005 0)
			(size 0.4572 0.508)
			(layers "B.Cu" "B.Mask" "B.Paste")
			(net "T2_NODE4_EN")
		)
		(pad "2" smd rect
			(at 0.40005 0)
			(size 0.4572 0.508)
			(layers "B.Cu" "B.Mask" "B.Paste")
			(net "P5V_NODE1")
		)
	)
)
